# SCM (Grand Teton) — schematic netlist excerpt (pin names and nets, part order shuffled) for the footprints in the layout excerpt that follows; sources: Cadence DE-HDL packaged netlist, KiCad conversion of 12092022_DA0F0TMDCD0_F0T_Management_Board_D_brd_V3_OCP.brd

R44  Q_RES  4.7K 1% EMPTY  pkg 0402LF  page 11 : A = P3V3_AUX ; B = SYS_PWRBTN_N
R770  Q_RES  4.7K 1% EMPTY  pkg 0402LF  page 27 : A = GND ; B = UART_BMC_5_TXD_R

(kicad_pcb
	(version 20260206)
	(generator "pcbnew")
	(generator_version "10.0")
	(general
		(thickness 1.6)
		(legacy_teardrops no)
	)
	(paper "A4")
	(title_block
		(title "12092022_DA0F0TMDCD0_F0T_Management_Board_D_brd_V3_OCP.brd")
		(comment 1 "Grand Teton / footprints 909-910 of 1440")
	)
	(layers
		(0 "F.Cu" signal "TOP")
		(4 "In1.Cu" signal "GND")
		(6 "In2.Cu" signal "IN1")
		(8 "In3.Cu" signal "GND1")
		(10 "In4.Cu" signal "IN2")
		(12 "In5.Cu" signal "VCC")
		(14 "In6.Cu" signal "VCC1")
		(16 "In7.Cu" signal "IN3")
		(18 "In8.Cu" signal "GND2")
		(20 "In9.Cu" signal "IN4")
		(22 "In10.Cu" signal "GND3")
		(2 "B.Cu" signal "BOTTOM")
		(9 "F.Adhes" user "F.Adhesive")
		(11 "B.Adhes" user "B.Adhesive")
		(13 "F.Paste" user "Package Geometry/Pastemask Top")
		(15 "B.Paste" user "Package Geometry/Pastemask Bottom")
		(5 "F.SilkS" user "Ref Des/Silkscreen Top")
		(7 "B.SilkS" user "Ref Des/Silkscreen Bottom")
		(1 "F.Mask" user "Board Geometry/Soldermask Top")
		(3 "B.Mask" user "Board Geometry/Soldermask Bottom")
		(17 "Dwgs.User" user "User.Drawings")
		(19 "Cmts.User" user "User.Comments")
		(21 "Eco1.User" user "User.Eco1")
		(23 "Eco2.User" user "User.Eco2")
		(25 "Edge.Cuts" user "Board Geometry/Outline")
		(27 "Margin" user)
		(31 "F.CrtYd" user "Package Geometry/Place Bound Top")
		(29 "B.CrtYd" user "Package Geometry/Place Bound Bottom")
		(35 "F.Fab" user "Ref Des/Assembly Top")
		(33 "B.Fab" user "Ref Des/Assembly Bottom")
	)
	(footprint ""
		(layer "B.Cu")
		(at 47.55388 -88.265 90)
		(property "Reference" "R770"
			(at 0 0 90)
			(layer "B.SilkS")
			(hide yes)
			(effects
				(font
					(size 1.27 1.27)
				)
				(justify mirror)
			)
		)
		(property "Value" ""
			(at 0 0 90)
			(layer "B.Fab")
			(effects
				(font
					(size 1.27 1.27)
				)
				(justify mirror)
			)
		)
		(duplicate_pad_numbers_are_jumpers no)
		(fp_line
			(start 0.7874 -0.4064)
			(end -0.7874 -0.4064)
			(stroke
				(width 0.1524)
				(type default)
			)
			(layer "B.SilkS")
		)
		(fp_line
			(start -0.7874 -0.4064)
			(end -0.7874 0.4064)
			(stroke
				(width 0.1524)
				(type default)
			)
			(layer "B.SilkS")
		)
		(fp_line
			(start 0.7874 0.4064)
			(end 0.7874 -0.4064)
			(stroke
				(width 0.1524)
				(type default)
			)
			(layer "B.SilkS")
		)
		(fp_line
			(start -0.7874 0.4064)
			(end 0.7874 0.4064)
			(stroke
				(width 0.1524)
				(type default)
			)
			(layer "B.SilkS")
		)
		(fp_line
			(start 0.67945 -0.305054)
			(end 0.12065 -0.305054)
			(stroke
				(width 0.1)
				(type default)
			)
			(layer "B.Fab")
		)
		(fp_line
			(start 0.12065 -0.305054)
			(end 0.12065 -0.2794)
			(stroke
				(width 0.1)
				(type default)
			)
			(layer "B.Fab")
		)
		(fp_line
			(start -0.12065 -0.3048)
			(end -0.67945 -0.3048)
			(stroke
				(width 0.1)
				(type default)
			)
			(layer "B.Fab")
		)
		(fp_line
			(start -0.67945 -0.3048)
			(end -0.67945 0.3048)
			(stroke
				(width 0.1)
				(type default)
			)
			(layer "B.Fab")
		)
		(fp_line
			(start 0.12065 -0.2794)
			(end -0.12065 -0.2794)
			(stroke
				(width 0.1)
				(type default)
			)
			(layer "B.Fab")
		)
		(fp_line
			(start -0.12065 -0.2794)
			(end -0.12065 -0.3048)
			(stroke
				(width 0.1)
				(type default)
			)
			(layer "B.Fab")
		)
		(fp_line
			(start 0.12065 0.2794)
			(end 0.12065 0.3048)
			(stroke
				(width 0.1)
				(type default)
			)
			(layer "B.Fab")
		)
		(fp_line
			(start -0.120396 0.2794)
			(end 0.12065 0.2794)
			(stroke
				(width 0.1)
				(type default)
			)
			(layer "B.Fab")
		)
		(fp_line
			(start 0.67945 0.3048)
			(end 0.67945 -0.305054)
			(stroke
				(width 0.1)
				(type default)
			)
			(layer "B.Fab")
		)
		(fp_line
			(start 0.12065 0.3048)
			(end 0.67945 0.3048)
			(stroke
				(width 0.1)
				(type default)
			)
			(layer "B.Fab")
		)
		(fp_line
			(start -0.120396 0.3048)
			(end -0.120396 0.2794)
			(stroke
				(width 0.1)
				(type default)
			)
			(layer "B.Fab")
		)
		(fp_line
			(start -0.67945 0.3048)
			(end -0.120396 0.3048)
			(stroke
				(width 0.1)
				(type default)
			)
			(layer "B.Fab")
		)
		(pad "1" smd circle
			(at 0.40005 0 270)
			(size 0 0)
			(layers "B.Cu" "B.Mask" "B.Paste")
			(net "GND")
		)
		(pad "2" smd circle
			(at -0.40005 0 270)
			(size 0 0)
			(layers "B.Cu" "B.Mask" "B.Paste")
			(net "UART_BMC_5_TXD_R")
		)
	)
	(footprint ""
		(layer "B.Cu")
		(at 24.590756 -106.50982 -90)
		(property "Reference" "R44"
			(at 0 0 90)
			(layer "B.SilkS")
			(hide yes)
			(effects
				(font
					(size 1.27 1.27)
				)
				(justify mirror)
			)
		)
		(property "Value" ""
			(at 0 0 90)
			(layer "B.Fab")
			(effects
				(font
					(size 1.27 1.27)
				)
				(justify mirror)
			)
		)
		(duplicate_pad_numbers_are_jumpers no)
		(fp_line
			(start -0.7874 0.4064)
			(end 0.7874 0.4064)
			(stroke
				(width 0.1524)
				(type default)
			)
			(layer "B.SilkS")
		)
		(fp_line
			(start 0.7874 0.4064)
			(end 0.7874 -0.4064)
			(stroke
				(width 0.1524)
				(type default)
			)
			(layer "B.SilkS")
		)
		(fp_line
			(start -0.7874 -0.4064)
			(end -0.7874 0.4064)
			(stroke
				(width 0.1524)
				(type default)
			)
			(layer "B.SilkS")
		)
		(fp_line
			(start 0.7874 -0.4064)
			(end -0.7874 -0.4064)
			(stroke
				(width 0.1524)
				(type default)
			)
			(layer "B.SilkS")
		)
		(fp_line
			(start -0.67945 0.3048)
			(end -0.120396 0.3048)
			(stroke
				(width 0.1)
				(type default)
			)
			(layer "B.Fab")
		)
		(fp_line
			(start -0.120396 0.3048)
			(end -0.120396 0.2794)
			(stroke
				(width 0.1)
				(type default)
			)
			(layer "B.Fab")
		)
		(fp_line
			(start 0.12065 0.3048)
			(end 0.67945 0.3048)
			(stroke
				(width 0.1)
				(type default)
			)
			(layer "B.Fab")
		)
		(fp_line
			(start 0.67945 0.3048)
			(end 0.67945 -0.305054)
			(stroke
				(width 0.1)
				(type default)
			)
			(layer "B.Fab")
		)
		(fp_line
			(start -0.120396 0.2794)
			(end 0.12065 0.2794)
			(stroke
				(width 0.1)
				(type default)
			)
			(layer "B.Fab")
		)
		(fp_line
			(start 0.12065 0.2794)
			(end 0.12065 0.3048)
			(stroke
				(width 0.1)
				(type default)
			)
			(layer "B.Fab")
		)
		(fp_line
			(start -0.12065 -0.2794)
			(end -0.12065 -0.3048)
			(stroke
				(width 0.1)
				(type default)
			)
			(layer "B.Fab")
		)
		(fp_line
			(start 0.12065 -0.2794)
			(end -0.12065 -0.2794)
			(stroke
				(width 0.1)
				(type default)
			)
			(layer "B.Fab")
		)
		(fp_line
			(start -0.67945 -0.3048)
			(end -0.67945 0.3048)
			(stroke
				(width 0.1)
				(type default)
			)
			(layer "B.Fab")
		)
		(fp_line
			(start -0.12065 -0.3048)
			(end -0.67945 -0.3048)
			(stroke
				(width 0.1)
				(type default)
			)
			(layer "B.Fab")
		)
		(fp_line
			(start 0.12065 -0.305054)
			(end 0.12065 -0.2794)
			(stroke
				(width 0.1)
				(type default)
			)
			(layer "B.Fab")
		)
		(fp_line
			(start 0.67945 -0.305054)
			(end 0.12065 -0.305054)
			(stroke
				(width 0.1)
				(type default)
			)
			(layer "B.Fab")
		)
		(pad "1" smd circle
			(at 0.40005 0 90)
			(size 0 0)
			(layers "B.Cu" "B.Mask" "B.Paste")
			(net "P3V3_AUX")
		)
		(pad "2" smd circle
			(at -0.40005 0 90)
			(size 0 0)
			(layers "B.Cu" "B.Mask" "B.Paste")
			(net "SYS_PWRBTN_N")
		)
	)
)
